(kicad_pcb
	(version 20260206)
	(generator "pcbnew")
	(generator_version "10.0")
	(general
		(thickness 1.6)
		(legacy_teardrops no)
	)
	(paper "A4")
	(title_block
		(title "Wiwynn_Tioga_Pass_MB.brd")
		(comment 1 "Tioga Pass / footprint 2445 of 4770 (J9M1), pads 1-123 of 291")
	)
	(layers
		(0 "F.Cu" signal "TOP")
		(4 "In1.Cu" signal "L2GND")
		(6 "In2.Cu" signal "L3")
		(8 "In3.Cu" signal "L4GND")
		(10 "In4.Cu" signal "L5")
		(12 "In5.Cu" signal "L6GND")
		(14 "In6.Cu" signal "L7VCC")
		(16 "In7.Cu" signal "L8VCC")
		(18 "In8.Cu" signal "L9GND")
		(20 "In9.Cu" signal "L10")
		(22 "In10.Cu" signal "L11GND")
		(24 "In11.Cu" signal "L12")
		(26 "In12.Cu" signal "L13GND")
		(2 "B.Cu" signal "BOTTOM")
		(9 "F.Adhes" user "F.Adhesive")
		(11 "B.Adhes" user "B.Adhesive")
		(13 "F.Paste" user "Package Geometry/Pastemask Top")
		(15 "B.Paste" user "Package Geometry/Pastemask Bottom")
		(5 "F.SilkS" user "Ref Des/Silkscreen Top")
		(7 "B.SilkS" user "Ref Des/Silkscreen Bottom")
		(1 "F.Mask" user "Board Geometry/Soldermask Top")
		(3 "B.Mask" user "Board Geometry/Soldermask Bottom")
		(17 "Dwgs.User" user "User.Drawings")
		(19 "Cmts.User" user "User.Comments")
		(21 "Eco1.User" user "User.Eco1")
		(23 "Eco2.User" user "User.Eco2")
		(25 "Edge.Cuts" user "Board Geometry/Outline")
		(27 "Margin" user)
		(31 "F.CrtYd" user "Package Geometry/Place Bound Top")
		(29 "B.CrtYd" user "Package Geometry/Place Bound Bottom")
		(35 "F.Fab" user "Ref Des/Assembly Top")
		(33 "B.Fab" user "Ref Des/Assembly Bottom")
	)
	(footprint ""
		(layer "B.Cu")
		(at 29.699458 -132.876036 90)
		(property "Reference" "J9M1"
			(at 2.352548 37.991542 0)
			(unlocked yes)
			(layer "B.SilkS")
			(effects
				(font
					(size 0.7874 0.5842)
					(thickness 0.1524)
				)
				(justify left mirror)
			)
		)
		(property "Value" ""
			(at 0 0 90)
			(layer "B.Fab")
			(effects
				(font
					(size 1.27 1.27)
				)
				(justify mirror)
			)
		)
		(duplicate_pad_numbers_are_jumpers no)
		(pad "" thru_hole circle
			(at -2.29997 -5.649976 270)
			(size 2.8194 2.8194)
			(drill 2.4384)
			(layers "*.Cu" "*.Mask")
			(remove_unused_layers no)
			(clearance 0.127)
			(thermal_gap 0.127)
		)
		(pad "" thru_hole oval
			(at -2.29997 68.90004 270)
			(size 2.8194 1.5748)
			(drill oval 2.4384 1.1938)
			(layers "*.Cu" "*.Mask")
			(remove_unused_layers no)
			(clearance 0.127)
			(thermal_gap 0.127)
		)
		(pad "" thru_hole circle
			(at -2.29997 132.299964 270)
			(size 2.8194 2.8194)
			(drill 2.4384)
			(layers "*.Cu" "*.Mask")
			(remove_unused_layers no)
			(clearance 0.127)
			(thermal_gap 0.127)
		)
		(pad "1" smd rect
			(at 0 0 270)
			(size 1.8034 0.508)
			(layers "B.Cu" "B.Mask" "B.Paste")
			(net "P12V_NVDIMM_KLM")
		)
		(pad "2" smd rect
			(at 0 0.849884 270)
			(size 1.8034 0.508)
			(layers "B.Cu" "B.Mask" "B.Paste")
			(net "GND")
		)
		(pad "3" smd rect
			(at 0 1.700022 270)
			(size 1.8034 0.508)
			(layers "B.Cu" "B.Mask" "B.Paste")
			(net "M_K_DQ<4>")
		)
		(pad "4" smd rect
			(at 0 2.549906 270)
			(size 1.8034 0.508)
			(layers "B.Cu" "B.Mask" "B.Paste")
			(net "GND")
		)
		(pad "5" smd rect
			(at 0 3.400044 270)
			(size 1.8034 0.508)
			(layers "B.Cu" "B.Mask" "B.Paste")
			(net "M_K_DQ<0>")
		)
		(pad "6" smd rect
			(at 0 4.249928 270)
			(size 1.8034 0.508)
			(layers "B.Cu" "B.Mask" "B.Paste")
			(net "GND")
		)
		(pad "7" smd rect
			(at 0 5.100066 270)
			(size 1.8034 0.508)
			(layers "B.Cu" "B.Mask" "B.Paste")
			(net "M_K_DQS_DP<9>")
		)
		(pad "8" smd rect
			(at 0 5.94995 270)
			(size 1.8034 0.508)
			(layers "B.Cu" "B.Mask" "B.Paste")
			(net "M_K_DQS_DN<9>")
		)
		(pad "9" smd rect
			(at 0 6.800088 270)
			(size 1.8034 0.508)
			(layers "B.Cu" "B.Mask" "B.Paste")
			(net "GND")
		)
		(pad "10" smd rect
			(at 0 7.649972 270)
			(size 1.8034 0.508)
			(layers "B.Cu" "B.Mask" "B.Paste")
			(net "M_K_DQ<6>")
		)
		(pad "11" smd rect
			(at 0 8.50011 270)
			(size 1.8034 0.508)
			(layers "B.Cu" "B.Mask" "B.Paste")
			(net "GND")
		)
		(pad "12" smd rect
			(at 0 9.349994 270)
			(size 1.8034 0.508)
			(layers "B.Cu" "B.Mask" "B.Paste")
			(net "M_K_DQ<2>")
		)
		(pad "13" smd rect
			(at 0 10.199878 270)
			(size 1.8034 0.508)
			(layers "B.Cu" "B.Mask" "B.Paste")
			(net "GND")
		)
		(pad "14" smd rect
			(at 0 11.050016 270)
			(size 1.8034 0.508)
			(layers "B.Cu" "B.Mask" "B.Paste")
			(net "M_K_DQ<12>")
		)
		(pad "15" smd rect
			(at 0 11.8999 270)
			(size 1.8034 0.508)
			(layers "B.Cu" "B.Mask" "B.Paste")
			(net "GND")
		)
		(pad "16" smd rect
			(at 0 12.750038 270)
			(size 1.8034 0.508)
			(layers "B.Cu" "B.Mask" "B.Paste")
			(net "M_K_DQ<8>")
		)
		(pad "17" smd rect
			(at 0 13.599922 270)
			(size 1.8034 0.508)
			(layers "B.Cu" "B.Mask" "B.Paste")
			(net "GND")
		)
		(pad "18" smd rect
			(at 0 14.45006 270)
			(size 1.8034 0.508)
			(layers "B.Cu" "B.Mask" "B.Paste")
			(net "M_K_DQS_DP<10>")
		)
		(pad "19" smd rect
			(at 0 15.299944 270)
			(size 1.8034 0.508)
			(layers "B.Cu" "B.Mask" "B.Paste")
			(net "M_K_DQS_DN<10>")
		)
		(pad "20" smd rect
			(at 0 16.150082 270)
			(size 1.8034 0.508)
			(layers "B.Cu" "B.Mask" "B.Paste")
			(net "GND")
		)
		(pad "21" smd rect
			(at 0 16.999966 270)
			(size 1.8034 0.508)
			(layers "B.Cu" "B.Mask" "B.Paste")
			(net "M_K_DQ<14>")
		)
		(pad "22" smd rect
			(at 0 17.850104 270)
			(size 1.8034 0.508)
			(layers "B.Cu" "B.Mask" "B.Paste")
			(net "GND")
		)
		(pad "23" smd rect
			(at 0 18.699988 270)
			(size 1.8034 0.508)
			(layers "B.Cu" "B.Mask" "B.Paste")
			(net "M_K_DQ<10>")
		)
		(pad "24" smd rect
			(at 0 19.550126 270)
			(size 1.8034 0.508)
			(layers "B.Cu" "B.Mask" "B.Paste")
			(net "GND")
		)
		(pad "25" smd rect
			(at 0 20.40001 270)
			(size 1.8034 0.508)
			(layers "B.Cu" "B.Mask" "B.Paste")
			(net "M_K_DQ<20>")
		)
		(pad "26" smd rect
			(at 0 21.249894 270)
			(size 1.8034 0.508)
			(layers "B.Cu" "B.Mask" "B.Paste")
			(net "GND")
		)
		(pad "27" smd rect
			(at 0 22.100032 270)
			(size 1.8034 0.508)
			(layers "B.Cu" "B.Mask" "B.Paste")
			(net "M_K_DQ<16>")
		)
		(pad "28" smd rect
			(at 0 22.949916 270)
			(size 1.8034 0.508)
			(layers "B.Cu" "B.Mask" "B.Paste")
			(net "GND")
		)
		(pad "29" smd rect
			(at 0 23.800054 270)
			(size 1.8034 0.508)
			(layers "B.Cu" "B.Mask" "B.Paste")
			(net "M_K_DQS_DP<11>")
		)
		(pad "30" smd rect
			(at 0 24.649938 270)
			(size 1.8034 0.508)
			(layers "B.Cu" "B.Mask" "B.Paste")
			(net "M_K_DQS_DN<11>")
		)
		(pad "31" smd rect
			(at 0 25.500076 270)
			(size 1.8034 0.508)
			(layers "B.Cu" "B.Mask" "B.Paste")
			(net "GND")
		)
		(pad "32" smd rect
			(at 0 26.34996 270)
			(size 1.8034 0.508)
			(layers "B.Cu" "B.Mask" "B.Paste")
			(net "M_K_DQ<22>")
		)
		(pad "33" smd rect
			(at 0 27.200098 270)
			(size 1.8034 0.508)
			(layers "B.Cu" "B.Mask" "B.Paste")
			(net "GND")
		)
		(pad "34" smd rect
			(at 0 28.049982 270)
			(size 1.8034 0.508)
			(layers "B.Cu" "B.Mask" "B.Paste")
			(net "M_K_DQ<18>")
		)
		(pad "35" smd rect
			(at 0 28.90012 270)
			(size 1.8034 0.508)
			(layers "B.Cu" "B.Mask" "B.Paste")
			(net "GND")
		)
		(pad "36" smd rect
			(at 0 29.750004 270)
			(size 1.8034 0.508)
			(layers "B.Cu" "B.Mask" "B.Paste")
			(net "M_K_DQ<28>")
		)
		(pad "37" smd rect
			(at 0 30.599888 270)
			(size 1.8034 0.508)
			(layers "B.Cu" "B.Mask" "B.Paste")
			(net "GND")
		)
		(pad "38" smd rect
			(at 0 31.450026 270)
			(size 1.8034 0.508)
			(layers "B.Cu" "B.Mask" "B.Paste")
			(net "M_K_DQ<24>")
		)
		(pad "39" smd rect
			(at 0 32.29991 270)
			(size 1.8034 0.508)
			(layers "B.Cu" "B.Mask" "B.Paste")
			(net "GND")
		)
		(pad "40" smd rect
			(at 0 33.150048 270)
			(size 1.8034 0.508)
			(layers "B.Cu" "B.Mask" "B.Paste")
			(net "M_K_DQS_DP<12>")
		)
		(pad "41" smd rect
			(at 0 33.999932 270)
			(size 1.8034 0.508)
			(layers "B.Cu" "B.Mask" "B.Paste")
			(net "M_K_DQS_DN<12>")
		)
		(pad "42" smd rect
			(at 0 34.85007 270)
			(size 1.8034 0.508)
			(layers "B.Cu" "B.Mask" "B.Paste")
			(net "GND")
		)
		(pad "43" smd rect
			(at 0 35.699954 270)
			(size 1.8034 0.508)
			(layers "B.Cu" "B.Mask" "B.Paste")
			(net "M_K_DQ<30>")
		)
		(pad "44" smd rect
			(at 0 36.550092 270)
			(size 1.8034 0.508)
			(layers "B.Cu" "B.Mask" "B.Paste")
			(net "GND")
		)
		(pad "45" smd rect
			(at 0 37.399976 270)
			(size 1.8034 0.508)
			(layers "B.Cu" "B.Mask" "B.Paste")
			(net "M_K_DQ<26>")
		)
		(pad "46" smd rect
			(at 0 38.250114 270)
			(size 1.8034 0.508)
			(layers "B.Cu" "B.Mask" "B.Paste")
			(net "GND")
		)
		(pad "47" smd rect
			(at 0 39.099998 270)
			(size 1.8034 0.508)
			(layers "B.Cu" "B.Mask" "B.Paste")
			(net "M_K_ECC<4>")
		)
		(pad "48" smd rect
			(at 0 39.949882 270)
			(size 1.8034 0.508)
			(layers "B.Cu" "B.Mask" "B.Paste")
			(net "GND")
		)
		(pad "49" smd rect
			(at 0 40.80002 270)
			(size 1.8034 0.508)
			(layers "B.Cu" "B.Mask" "B.Paste")
			(net "M_K_ECC<0>")
		)
		(pad "50" smd rect
			(at 0 41.649904 270)
			(size 1.8034 0.508)
			(layers "B.Cu" "B.Mask" "B.Paste")
			(net "GND")
		)
		(pad "51" smd rect
			(at 0 42.500042 270)
			(size 1.8034 0.508)
			(layers "B.Cu" "B.Mask" "B.Paste")
			(net "M_K_DQS_DP<17>")
		)
		(pad "52" smd rect
			(at 0 43.349926 270)
			(size 1.8034 0.508)
			(layers "B.Cu" "B.Mask" "B.Paste")
			(net "M_K_DQS_DN<17>")
		)
		(pad "53" smd rect
			(at 0 44.200064 270)
			(size 1.8034 0.508)
			(layers "B.Cu" "B.Mask" "B.Paste")
			(net "GND")
		)
		(pad "54" smd rect
			(at 0 45.049948 270)
			(size 1.8034 0.508)
			(layers "B.Cu" "B.Mask" "B.Paste")
			(net "M_K_ECC<6>")
		)
		(pad "55" smd rect
			(at 0 45.900086 270)
			(size 1.8034 0.508)
			(layers "B.Cu" "B.Mask" "B.Paste")
			(net "GND")
		)
		(pad "56" smd rect
			(at 0 46.74997 270)
			(size 1.8034 0.508)
			(layers "B.Cu" "B.Mask" "B.Paste")
			(net "M_K_ECC<2>")
		)
		(pad "57" smd rect
			(at 0 47.600108 270)
			(size 1.8034 0.508)
			(layers "B.Cu" "B.Mask" "B.Paste")
			(net "GND")
		)
		(pad "58" smd rect
			(at 0 48.449992 270)
			(size 1.8034 0.508)
			(layers "B.Cu" "B.Mask" "B.Paste")
			(net "M_KLM_RST_N")
		)
		(pad "59" smd rect
			(at 0 49.299876 270)
			(size 1.8034 0.508)
			(layers "B.Cu" "B.Mask" "B.Paste")
			(net "PVDDQ_KLM")
		)
		(pad "60" smd rect
			(at 0 50.150014 270)
			(size 1.8034 0.508)
			(layers "B.Cu" "B.Mask" "B.Paste")
			(net "M_K_CKE<2>")
		)
		(pad "61" smd rect
			(at 0 50.999898 270)
			(size 1.8034 0.508)
			(layers "B.Cu" "B.Mask" "B.Paste")
			(net "PVDDQ_KLM")
		)
		(pad "62" smd rect
			(at 0 51.850036 270)
			(size 1.8034 0.508)
			(layers "B.Cu" "B.Mask" "B.Paste")
			(net "M_K_ACT_N")
		)
		(pad "63" smd rect
			(at 0 52.69992 270)
			(size 1.8034 0.508)
			(layers "B.Cu" "B.Mask" "B.Paste")
			(net "M_K_BG<0>")
		)
		(pad "64" smd rect
			(at 0 53.550058 270)
			(size 1.8034 0.508)
			(layers "B.Cu" "B.Mask" "B.Paste")
			(net "PVDDQ_KLM")
		)
		(pad "65" smd rect
			(at 0 54.399942 270)
			(size 1.8034 0.508)
			(layers "B.Cu" "B.Mask" "B.Paste")
			(net "M_K_MA<12>")
		)
		(pad "66" smd rect
			(at 0 55.25008 270)
			(size 1.8034 0.508)
			(layers "B.Cu" "B.Mask" "B.Paste")
			(net "M_K_MA<9>")
		)
		(pad "67" smd rect
			(at 0 56.099964 270)
			(size 1.8034 0.508)
			(layers "B.Cu" "B.Mask" "B.Paste")
			(net "PVDDQ_KLM")
		)
		(pad "68" smd rect
			(at 0 56.950102 270)
			(size 1.8034 0.508)
			(layers "B.Cu" "B.Mask" "B.Paste")
			(net "M_K_MA<8>")
		)
		(pad "69" smd rect
			(at 0 57.799986 270)
			(size 1.8034 0.508)
			(layers "B.Cu" "B.Mask" "B.Paste")
			(net "M_K_MA<6>")
		)
		(pad "70" smd rect
			(at 0 58.650124 270)
			(size 1.8034 0.508)
			(layers "B.Cu" "B.Mask" "B.Paste")
			(net "PVDDQ_KLM")
		)
		(pad "71" smd rect
			(at 0 59.500008 270)
			(size 1.8034 0.508)
			(layers "B.Cu" "B.Mask" "B.Paste")
			(net "M_K_MA<3>")
		)
		(pad "72" smd rect
			(at 0 60.349892 270)
			(size 1.8034 0.508)
			(layers "B.Cu" "B.Mask" "B.Paste")
			(net "M_K_MA<1>")
		)
		(pad "73" smd rect
			(at 0 61.20003 270)
			(size 1.8034 0.508)
			(layers "B.Cu" "B.Mask" "B.Paste")
			(net "PVDDQ_KLM")
		)
		(pad "74" smd rect
			(at 0 62.049914 270)
			(size 1.8034 0.508)
			(layers "B.Cu" "B.Mask" "B.Paste")
			(net "M_K_CLK_DP<2>")
		)
		(pad "75" smd rect
			(at 0 62.900052 270)
			(size 1.8034 0.508)
			(layers "B.Cu" "B.Mask" "B.Paste")
			(net "M_K_CLK_DN<2>")
		)
		(pad "76" smd rect
			(at 0 63.749936 270)
			(size 1.8034 0.508)
			(layers "B.Cu" "B.Mask" "B.Paste")
			(net "PVDDQ_KLM")
		)
		(pad "77" smd rect
			(at 0 64.600074 270)
			(size 1.8034 0.508)
			(layers "B.Cu" "B.Mask" "B.Paste")
			(net "PVTT_KLM")
		)
		(pad "78" smd rect
			(at 0 70.550024 270)
			(size 1.8034 0.508)
			(layers "B.Cu" "B.Mask" "B.Paste")
			(net "FM_DIMM_EVENT_COD_N")
		)
		(pad "79" smd rect
			(at 0 71.399908 270)
			(size 1.8034 0.508)
			(layers "B.Cu" "B.Mask" "B.Paste")
			(net "M_K_MA<0>")
		)
		(pad "80" smd rect
			(at 0 72.250046 270)
			(size 1.8034 0.508)
			(layers "B.Cu" "B.Mask" "B.Paste")
			(net "PVDDQ_KLM")
		)
		(pad "81" smd rect
			(at 0 73.09993 270)
			(size 1.8034 0.508)
			(layers "B.Cu" "B.Mask" "B.Paste")
			(net "M_K_BA<0>")
		)
		(pad "82" smd rect
			(at 0 73.950068 270)
			(size 1.8034 0.508)
			(layers "B.Cu" "B.Mask" "B.Paste")
			(net "M_K_MA<16>")
		)
		(pad "83" smd rect
			(at 0 74.799952 270)
			(size 1.8034 0.508)
			(layers "B.Cu" "B.Mask" "B.Paste")
			(net "PVDDQ_KLM")
		)
		(pad "84" smd rect
			(at 0 75.65009 270)
			(size 1.8034 0.508)
			(layers "B.Cu" "B.Mask" "B.Paste")
			(net "M_K_CS_N<4>")
		)
		(pad "85" smd rect
			(at 0 76.499974 270)
			(size 1.8034 0.508)
			(layers "B.Cu" "B.Mask" "B.Paste")
			(net "PVDDQ_KLM")
		)
		(pad "86" smd rect
			(at 0 77.350112 270)
			(size 1.8034 0.508)
			(layers "B.Cu" "B.Mask" "B.Paste")
			(net "M_K_MA<15>")
		)
		(pad "87" smd rect
			(at 0 78.199996 270)
			(size 1.8034 0.508)
			(layers "B.Cu" "B.Mask" "B.Paste")
			(net "M_K_ODT<2>")
		)
		(pad "88" smd rect
			(at 0 79.04988 270)
			(size 1.8034 0.508)
			(layers "B.Cu" "B.Mask" "B.Paste")
			(net "PVDDQ_KLM")
		)
		(pad "89" smd rect
			(at 0 79.900018 270)
			(size 1.8034 0.508)
			(layers "B.Cu" "B.Mask" "B.Paste")
			(net "M_K_CS_N<5>")
		)
		(pad "90" smd rect
			(at 0 80.749902 270)
			(size 1.8034 0.508)
			(layers "B.Cu" "B.Mask" "B.Paste")
			(net "PVDDQ_KLM")
		)
		(pad "91" smd rect
			(at 0 81.60004 270)
			(size 1.8034 0.508)
			(layers "B.Cu" "B.Mask" "B.Paste")
			(net "M_K_ODT<3>")
		)
		(pad "92" smd rect
			(at 0 82.449924 270)
			(size 1.8034 0.508)
			(layers "B.Cu" "B.Mask" "B.Paste")
			(net "PVDDQ_KLM")
		)
		(pad "93" smd rect
			(at 0 83.300062 270)
			(size 1.8034 0.508)
			(layers "B.Cu" "B.Mask" "B.Paste")
			(net "M_K_CS_N<6>")
		)
		(pad "94" smd rect
			(at 0 84.149946 270)
			(size 1.8034 0.508)
			(layers "B.Cu" "B.Mask" "B.Paste")
			(net "GND")
		)
		(pad "95" smd rect
			(at 0 85.000084 270)
			(size 1.8034 0.508)
			(layers "B.Cu" "B.Mask" "B.Paste")
			(net "M_K_DQ<36>")
		)
		(pad "96" smd rect
			(at 0 85.849968 270)
			(size 1.8034 0.508)
			(layers "B.Cu" "B.Mask" "B.Paste")
			(net "GND")
		)
		(pad "97" smd rect
			(at 0 86.700106 270)
			(size 1.8034 0.508)
			(layers "B.Cu" "B.Mask" "B.Paste")
			(net "M_K_DQ<32>")
		)
		(pad "98" smd rect
			(at 0 87.54999 270)
			(size 1.8034 0.508)
			(layers "B.Cu" "B.Mask" "B.Paste")
			(net "GND")
		)
		(pad "99" smd rect
			(at 0 88.399874 270)
			(size 1.8034 0.508)
			(layers "B.Cu" "B.Mask" "B.Paste")
			(net "M_K_DQS_DP<13>")
		)
		(pad "100" smd rect
			(at 0 89.250012 270)
			(size 1.8034 0.508)
			(layers "B.Cu" "B.Mask" "B.Paste")
			(net "M_K_DQS_DN<13>")
		)
		(pad "101" smd rect
			(at 0 90.099896 270)
			(size 1.8034 0.508)
			(layers "B.Cu" "B.Mask" "B.Paste")
			(net "GND")
		)
		(pad "102" smd rect
			(at 0 90.950034 270)
			(size 1.8034 0.508)
			(layers "B.Cu" "B.Mask" "B.Paste")
			(net "M_K_DQ<38>")
		)
		(pad "103" smd rect
			(at 0 91.799918 270)
			(size 1.8034 0.508)
			(layers "B.Cu" "B.Mask" "B.Paste")
			(net "GND")
		)
		(pad "104" smd rect
			(at 0 92.650056 270)
			(size 1.8034 0.508)
			(layers "B.Cu" "B.Mask" "B.Paste")
			(net "M_K_DQ<34>")
		)
		(pad "105" smd rect
			(at 0 93.49994 270)
			(size 1.8034 0.508)
			(layers "B.Cu" "B.Mask" "B.Paste")
			(net "GND")
		)
		(pad "106" smd rect
			(at 0 94.350078 270)
			(size 1.8034 0.508)
			(layers "B.Cu" "B.Mask" "B.Paste")
			(net "M_K_DQ<44>")
		)
		(pad "107" smd rect
			(at 0 95.199962 270)
			(size 1.8034 0.508)
			(layers "B.Cu" "B.Mask" "B.Paste")
			(net "GND")
		)
		(pad "108" smd rect
			(at 0 96.0501 270)
			(size 1.8034 0.508)
			(layers "B.Cu" "B.Mask" "B.Paste")
			(net "M_K_DQ<40>")
		)
		(pad "109" smd rect
			(at 0 96.899984 270)
			(size 1.8034 0.508)
			(layers "B.Cu" "B.Mask" "B.Paste")
			(net "GND")
		)
		(pad "110" smd rect
			(at 0 97.750122 270)
			(size 1.8034 0.508)
			(layers "B.Cu" "B.Mask" "B.Paste")
			(net "M_K_DQS_DP<14>")
		)
		(pad "111" smd rect
			(at 0 98.600006 270)
			(size 1.8034 0.508)
			(layers "B.Cu" "B.Mask" "B.Paste")
			(net "M_K_DQS_DN<14>")
		)
		(pad "112" smd rect
			(at 0 99.44989 270)
			(size 1.8034 0.508)
			(layers "B.Cu" "B.Mask" "B.Paste")
			(net "GND")
		)
		(pad "113" smd rect
			(at 0 100.300028 270)
			(size 1.8034 0.508)
			(layers "B.Cu" "B.Mask" "B.Paste")
			(net "M_K_DQ<46>")
		)
		(pad "114" smd rect
			(at 0 101.149912 270)
			(size 1.8034 0.508)
			(layers "B.Cu" "B.Mask" "B.Paste")
			(net "GND")
		)
		(pad "115" smd rect
			(at 0 102.00005 270)
			(size 1.8034 0.508)
			(layers "B.Cu" "B.Mask" "B.Paste")
			(net "M_K_DQ<42>")
		)
		(pad "116" smd rect
			(at 0 102.849934 270)
			(size 1.8034 0.508)
			(layers "B.Cu" "B.Mask" "B.Paste")
			(net "GND")
		)
		(pad "117" smd rect
			(at 0 103.700072 270)
			(size 1.8034 0.508)
			(layers "B.Cu" "B.Mask" "B.Paste")
			(net "M_K_DQ<52>")
		)
		(pad "118" smd rect
			(at 0 104.549956 270)
			(size 1.8034 0.508)
			(layers "B.Cu" "B.Mask" "B.Paste")
			(net "GND")
		)
		(pad "119" smd rect
			(at 0 105.400094 270)
			(size 1.8034 0.508)
			(layers "B.Cu" "B.Mask" "B.Paste")
			(net "M_K_DQ<48>")
		)
		(pad "120" smd rect
			(at 0 106.249978 270)
			(size 1.8034 0.508)
			(layers "B.Cu" "B.Mask" "B.Paste")
			(net "GND")
		)
	)
)
